(kicad_pcb
	(version 20260206)
	(generator "pcbnew")
	(generator_version "10.0")
	(general
		(thickness 1.6)
		(legacy_teardrops no)
	)
	(paper "A4")
	(title_block
		(title "03242023_DA0F0TMBIJ0_F0T_Motherboard_J_brd_V01_OCP.brd")
		(comment 1 "Grand Teton / footprints 3344-3348 of 6105")
	)
	(layers
		(0 "F.Cu" signal "TOP")
		(4 "In1.Cu" signal "GND")
		(6 "In2.Cu" signal "IN1")
		(8 "In3.Cu" signal "GND1")
		(10 "In4.Cu" signal "IN2")
		(12 "In5.Cu" signal "GND2")
		(14 "In6.Cu" signal "IN3")
		(16 "In7.Cu" signal "GND3")
		(18 "In8.Cu" signal "VCC")
		(20 "In9.Cu" signal "VCC1")
		(22 "In10.Cu" signal "GND4")
		(24 "In11.Cu" signal "IN4")
		(26 "In12.Cu" signal "GND5")
		(28 "In13.Cu" signal "IN5")
		(30 "In14.Cu" signal "GND6")
		(32 "In15.Cu" signal "IN6")
		(34 "In16.Cu" signal "GND7")
		(2 "B.Cu" signal "BOTTOM")
		(9 "F.Adhes" user "F.Adhesive")
		(11 "B.Adhes" user "B.Adhesive")
		(13 "F.Paste" user "Package Geometry/Pastemask Top")
		(15 "B.Paste" user "Package Geometry/Pastemask Bottom")
		(5 "F.SilkS" user "Ref Des/Silkscreen Top")
		(7 "B.SilkS" user "Ref Des/Silkscreen Bottom")
		(1 "F.Mask" user "Board Geometry/Soldermask Top")
		(3 "B.Mask" user "Board Geometry/Soldermask Bottom")
		(17 "Dwgs.User" user "User.Drawings")
		(19 "Cmts.User" user "User.Comments")
		(21 "Eco1.User" user "User.Eco1")
		(23 "Eco2.User" user "User.Eco2")
		(25 "Edge.Cuts" user "Board Geometry/Outline")
		(27 "Margin" user)
		(31 "F.CrtYd" user "Package Geometry/Place Bound Top")
		(29 "B.CrtYd" user "Package Geometry/Place Bound Bottom")
		(35 "F.Fab" user "Ref Des/Assembly Top")
		(33 "B.Fab" user "Ref Des/Assembly Bottom")
	)
	(footprint ""
		(layer "F.Cu")
		(at 420.774114 -362.155994 -90)
		(property "Reference" "PC602_P0_1"
			(at 0 0 270)
			(layer "F.SilkS")
			(hide yes)
			(effects
				(font
					(size 1.27 1.27)
				)
			)
		)
		(property "Value" ""
			(at 0 0 270)
			(layer "F.Fab")
			(effects
				(font
					(size 1.27 1.27)
				)
			)
		)
		(duplicate_pad_numbers_are_jumpers no)
		(fp_line
			(start -0.7874 0.4064)
			(end -0.7874 -0.4064)
			(stroke
				(width 0.1524)
				(type default)
			)
			(layer "F.SilkS")
		)
		(fp_line
			(start 0.7874 0.4064)
			(end -0.7874 0.4064)
			(stroke
				(width 0.1524)
				(type default)
			)
			(layer "F.SilkS")
		)
		(fp_line
			(start -0.7874 -0.4064)
			(end 0.7874 -0.4064)
			(stroke
				(width 0.1524)
				(type default)
			)
			(layer "F.SilkS")
		)
		(fp_line
			(start 0.7874 -0.4064)
			(end 0.7874 0.4064)
			(stroke
				(width 0.1524)
				(type default)
			)
			(layer "F.SilkS")
		)
		(fp_line
			(start -0.67945 0.3048)
			(end -0.67945 -0.305054)
			(stroke
				(width 0.1)
				(type default)
			)
			(layer "F.Fab")
		)
		(fp_line
			(start -0.12065 0.3048)
			(end -0.67945 0.3048)
			(stroke
				(width 0.1)
				(type default)
			)
			(layer "F.Fab")
		)
		(fp_line
			(start 0.120396 0.3048)
			(end 0.120396 0.2794)
			(stroke
				(width 0.1)
				(type default)
			)
			(layer "F.Fab")
		)
		(fp_line
			(start 0.67945 0.3048)
			(end 0.120396 0.3048)
			(stroke
				(width 0.1)
				(type default)
			)
			(layer "F.Fab")
		)
		(fp_line
			(start -0.12065 0.2794)
			(end -0.12065 0.3048)
			(stroke
				(width 0.1)
				(type default)
			)
			(layer "F.Fab")
		)
		(fp_line
			(start 0.120396 0.2794)
			(end -0.12065 0.2794)
			(stroke
				(width 0.1)
				(type default)
			)
			(layer "F.Fab")
		)
		(fp_line
			(start -0.12065 -0.2794)
			(end 0.12065 -0.2794)
			(stroke
				(width 0.1)
				(type default)
			)
			(layer "F.Fab")
		)
		(fp_line
			(start 0.12065 -0.2794)
			(end 0.12065 -0.3048)
			(stroke
				(width 0.1)
				(type default)
			)
			(layer "F.Fab")
		)
		(fp_line
			(start 0.12065 -0.3048)
			(end 0.67945 -0.3048)
			(stroke
				(width 0.1)
				(type default)
			)
			(layer "F.Fab")
		)
		(fp_line
			(start 0.67945 -0.3048)
			(end 0.67945 0.3048)
			(stroke
				(width 0.1)
				(type default)
			)
			(layer "F.Fab")
		)
		(fp_line
			(start -0.67945 -0.305054)
			(end -0.12065 -0.305054)
			(stroke
				(width 0.1)
				(type default)
			)
			(layer "F.Fab")
		)
		(fp_line
			(start -0.12065 -0.305054)
			(end -0.12065 -0.2794)
			(stroke
				(width 0.1)
				(type default)
			)
			(layer "F.Fab")
		)
		(pad "1" smd circle
			(at -0.40005 0 270)
			(size 0 0)
			(layers "F.Cu" "F.Mask" "F.Paste")
			(net "SW_P12V_PVCCFA_EHV_FIVRA_CPU0_R")
		)
		(pad "2" smd circle
			(at 0.40005 0 270)
			(size 0 0)
			(layers "F.Cu" "F.Mask" "F.Paste")
			(net "GND")
		)
	)
	(footprint ""
		(layer "F.Cu")
		(at 366.432338 -424.085766)
		(property "Reference" "R4180"
			(at 0 0 0)
			(layer "F.SilkS")
			(hide yes)
			(effects
				(font
					(size 1.27 1.27)
				)
			)
		)
		(property "Value" ""
			(at 0 0 0)
			(layer "F.Fab")
			(effects
				(font
					(size 1.27 1.27)
				)
			)
		)
		(duplicate_pad_numbers_are_jumpers no)
		(fp_line
			(start -0.7874 -0.4064)
			(end 0.7874 -0.4064)
			(stroke
				(width 0.1524)
				(type default)
			)
			(layer "F.SilkS")
		)
		(fp_line
			(start -0.7874 0.4064)
			(end -0.7874 -0.4064)
			(stroke
				(width 0.1524)
				(type default)
			)
			(layer "F.SilkS")
		)
		(fp_line
			(start 0.7874 -0.4064)
			(end 0.7874 0.4064)
			(stroke
				(width 0.1524)
				(type default)
			)
			(layer "F.SilkS")
		)
		(fp_line
			(start 0.7874 0.4064)
			(end -0.7874 0.4064)
			(stroke
				(width 0.1524)
				(type default)
			)
			(layer "F.SilkS")
		)
		(fp_line
			(start -0.67945 -0.305054)
			(end -0.12065 -0.305054)
			(stroke
				(width 0.1)
				(type default)
			)
			(layer "F.Fab")
		)
		(fp_line
			(start -0.67945 0.3048)
			(end -0.67945 -0.305054)
			(stroke
				(width 0.1)
				(type default)
			)
			(layer "F.Fab")
		)
		(fp_line
			(start -0.12065 -0.305054)
			(end -0.12065 -0.2794)
			(stroke
				(width 0.1)
				(type default)
			)
			(layer "F.Fab")
		)
		(fp_line
			(start -0.12065 -0.2794)
			(end 0.12065 -0.2794)
			(stroke
				(width 0.1)
				(type default)
			)
			(layer "F.Fab")
		)
		(fp_line
			(start -0.12065 0.2794)
			(end -0.12065 0.3048)
			(stroke
				(width 0.1)
				(type default)
			)
			(layer "F.Fab")
		)
		(fp_line
			(start -0.12065 0.3048)
			(end -0.67945 0.3048)
			(stroke
				(width 0.1)
				(type default)
			)
			(layer "F.Fab")
		)
		(fp_line
			(start 0.120396 0.2794)
			(end -0.12065 0.2794)
			(stroke
				(width 0.1)
				(type default)
			)
			(layer "F.Fab")
		)
		(fp_line
			(start 0.120396 0.3048)
			(end 0.120396 0.2794)
			(stroke
				(width 0.1)
				(type default)
			)
			(layer "F.Fab")
		)
		(fp_line
			(start 0.12065 -0.3048)
			(end 0.67945 -0.3048)
			(stroke
				(width 0.1)
				(type default)
			)
			(layer "F.Fab")
		)
		(fp_line
			(start 0.12065 -0.2794)
			(end 0.12065 -0.3048)
			(stroke
				(width 0.1)
				(type default)
			)
			(layer "F.Fab")
		)
		(fp_line
			(start 0.67945 -0.3048)
			(end 0.67945 0.3048)
			(stroke
				(width 0.1)
				(type default)
			)
			(layer "F.Fab")
		)
		(fp_line
			(start 0.67945 0.3048)
			(end 0.120396 0.3048)
			(stroke
				(width 0.1)
				(type default)
			)
			(layer "F.Fab")
		)
		(pad "1" smd circle
			(at -0.40005 0)
			(size 0 0)
			(layers "F.Cu" "F.Mask" "F.Paste")
			(net "SMB_LM75_0_3V3AUX_SCL")
		)
		(pad "2" smd circle
			(at 0.40005 0)
			(size 0 0)
			(layers "F.Cu" "F.Mask" "F.Paste")
			(net "SMB_LM75_0_3V3AUX_SCL_R1")
		)
	)
	(footprint ""
		(layer "F.Cu")
		(at 309.57774 -433.12461 90)
		(property "Reference" "R4130"
			(at 0 0 90)
			(layer "F.SilkS")
			(hide yes)
			(effects
				(font
					(size 1.27 1.27)
				)
			)
		)
		(property "Value" ""
			(at 0 0 90)
			(layer "F.Fab")
			(effects
				(font
					(size 1.27 1.27)
				)
			)
		)
		(duplicate_pad_numbers_are_jumpers no)
		(fp_line
			(start 0.7874 -0.4064)
			(end 0.7874 0.4064)
			(stroke
				(width 0.1524)
				(type default)
			)
			(layer "F.SilkS")
		)
		(fp_line
			(start -0.7874 -0.4064)
			(end 0.7874 -0.4064)
			(stroke
				(width 0.1524)
				(type default)
			)
			(layer "F.SilkS")
		)
		(fp_line
			(start 0.7874 0.4064)
			(end -0.7874 0.4064)
			(stroke
				(width 0.1524)
				(type default)
			)
			(layer "F.SilkS")
		)
		(fp_line
			(start -0.7874 0.4064)
			(end -0.7874 -0.4064)
			(stroke
				(width 0.1524)
				(type default)
			)
			(layer "F.SilkS")
		)
		(fp_line
			(start -0.12065 -0.305054)
			(end -0.12065 -0.2794)
			(stroke
				(width 0.1)
				(type default)
			)
			(layer "F.Fab")
		)
		(fp_line
			(start -0.67945 -0.305054)
			(end -0.12065 -0.305054)
			(stroke
				(width 0.1)
				(type default)
			)
			(layer "F.Fab")
		)
		(fp_line
			(start 0.67945 -0.3048)
			(end 0.67945 0.3048)
			(stroke
				(width 0.1)
				(type default)
			)
			(layer "F.Fab")
		)
		(fp_line
			(start 0.12065 -0.3048)
			(end 0.67945 -0.3048)
			(stroke
				(width 0.1)
				(type default)
			)
			(layer "F.Fab")
		)
		(fp_line
			(start 0.12065 -0.2794)
			(end 0.12065 -0.3048)
			(stroke
				(width 0.1)
				(type default)
			)
			(layer "F.Fab")
		)
		(fp_line
			(start -0.12065 -0.2794)
			(end 0.12065 -0.2794)
			(stroke
				(width 0.1)
				(type default)
			)
			(layer "F.Fab")
		)
		(fp_line
			(start 0.120396 0.2794)
			(end -0.12065 0.2794)
			(stroke
				(width 0.1)
				(type default)
			)
			(layer "F.Fab")
		)
		(fp_line
			(start -0.12065 0.2794)
			(end -0.12065 0.3048)
			(stroke
				(width 0.1)
				(type default)
			)
			(layer "F.Fab")
		)
		(fp_line
			(start 0.67945 0.3048)
			(end 0.120396 0.3048)
			(stroke
				(width 0.1)
				(type default)
			)
			(layer "F.Fab")
		)
		(fp_line
			(start 0.120396 0.3048)
			(end 0.120396 0.2794)
			(stroke
				(width 0.1)
				(type default)
			)
			(layer "F.Fab")
		)
		(fp_line
			(start -0.12065 0.3048)
			(end -0.67945 0.3048)
			(stroke
				(width 0.1)
				(type default)
			)
			(layer "F.Fab")
		)
		(fp_line
			(start -0.67945 0.3048)
			(end -0.67945 -0.305054)
			(stroke
				(width 0.1)
				(type default)
			)
			(layer "F.Fab")
		)
		(pad "1" smd circle
			(at -0.40005 0 90)
			(size 0 0)
			(layers "F.Cu" "F.Mask" "F.Paste")
			(net "P3V3_AUX")
		)
		(pad "2" smd circle
			(at 0.40005 0 90)
			(size 0 0)
			(layers "F.Cu" "F.Mask" "F.Paste")
			(net "GPU_3V3IO_RSVD1_FFU_ISO")
		)
	)
	(footprint ""
		(layer "F.Cu")
		(at 240.60785 -248.515378 -90)
		(property "Reference" "C2255"
			(at 0 0 270)
			(layer "F.SilkS")
			(hide yes)
			(effects
				(font
					(size 1.27 1.27)
				)
			)
		)
		(property "Value" ""
			(at 0 0 270)
			(layer "F.Fab")
			(effects
				(font
					(size 1.27 1.27)
				)
			)
		)
		(duplicate_pad_numbers_are_jumpers no)
		(fp_line
			(start -0.7874 0.4064)
			(end -0.7874 -0.4064)
			(stroke
				(width 0.1524)
				(type default)
			)
			(layer "F.SilkS")
		)
		(fp_line
			(start 0.7874 0.4064)
			(end -0.7874 0.4064)
			(stroke
				(width 0.1524)
				(type default)
			)
			(layer "F.SilkS")
		)
		(fp_line
			(start -0.7874 -0.4064)
			(end 0.7874 -0.4064)
			(stroke
				(width 0.1524)
				(type default)
			)
			(layer "F.SilkS")
		)
		(fp_line
			(start 0.7874 -0.4064)
			(end 0.7874 0.4064)
			(stroke
				(width 0.1524)
				(type default)
			)
			(layer "F.SilkS")
		)
		(fp_line
			(start -0.67945 0.3048)
			(end -0.67945 -0.305054)
			(stroke
				(width 0.1)
				(type default)
			)
			(layer "F.Fab")
		)
		(fp_line
			(start -0.12065 0.3048)
			(end -0.67945 0.3048)
			(stroke
				(width 0.1)
				(type default)
			)
			(layer "F.Fab")
		)
		(fp_line
			(start 0.120396 0.3048)
			(end 0.120396 0.2794)
			(stroke
				(width 0.1)
				(type default)
			)
			(layer "F.Fab")
		)
		(fp_line
			(start 0.67945 0.3048)
			(end 0.120396 0.3048)
			(stroke
				(width 0.1)
				(type default)
			)
			(layer "F.Fab")
		)
		(fp_line
			(start -0.12065 0.2794)
			(end -0.12065 0.3048)
			(stroke
				(width 0.1)
				(type default)
			)
			(layer "F.Fab")
		)
		(fp_line
			(start 0.120396 0.2794)
			(end -0.12065 0.2794)
			(stroke
				(width 0.1)
				(type default)
			)
			(layer "F.Fab")
		)
		(fp_line
			(start -0.12065 -0.2794)
			(end 0.12065 -0.2794)
			(stroke
				(width 0.1)
				(type default)
			)
			(layer "F.Fab")
		)
		(fp_line
			(start 0.12065 -0.2794)
			(end 0.12065 -0.3048)
			(stroke
				(width 0.1)
				(type default)
			)
			(layer "F.Fab")
		)
		(fp_line
			(start 0.12065 -0.3048)
			(end 0.67945 -0.3048)
			(stroke
				(width 0.1)
				(type default)
			)
			(layer "F.Fab")
		)
		(fp_line
			(start 0.67945 -0.3048)
			(end 0.67945 0.3048)
			(stroke
				(width 0.1)
				(type default)
			)
			(layer "F.Fab")
		)
		(fp_line
			(start -0.67945 -0.305054)
			(end -0.12065 -0.305054)
			(stroke
				(width 0.1)
				(type default)
			)
			(layer "F.Fab")
		)
		(fp_line
			(start -0.12065 -0.305054)
			(end -0.12065 -0.2794)
			(stroke
				(width 0.1)
				(type default)
			)
			(layer "F.Fab")
		)
		(pad "1" smd circle
			(at -0.40005 0 270)
			(size 0 0)
			(layers "F.Cu" "F.Mask" "F.Paste")
			(net "CLK_GEN2_XTAL_IN_R")
		)
		(pad "2" smd circle
			(at 0.40005 0 270)
			(size 0 0)
			(layers "F.Cu" "F.Mask" "F.Paste")
			(net "GND")
		)
	)
	(footprint ""
		(layer "F.Cu")
		(at 134.2136 -124.234448)
		(property "Reference" "R3149"
			(at 0 0 0)
			(layer "F.SilkS")
			(hide yes)
			(effects
				(font
					(size 1.27 1.27)
				)
			)
		)
		(property "Value" ""
			(at 0 0 0)
			(layer "F.Fab")
			(effects
				(font
					(size 1.27 1.27)
				)
			)
		)
		(duplicate_pad_numbers_are_jumpers no)
		(fp_line
			(start -0.7874 -0.4064)
			(end 0.7874 -0.4064)
			(stroke
				(width 0.1524)
				(type default)
			)
			(layer "F.SilkS")
		)
		(fp_line
			(start -0.7874 0.4064)
			(end -0.7874 -0.4064)
			(stroke
				(width 0.1524)
				(type default)
			)
			(layer "F.SilkS")
		)
		(fp_line
			(start 0.7874 -0.4064)
			(end 0.7874 0.4064)
			(stroke
				(width 0.1524)
				(type default)
			)
			(layer "F.SilkS")
		)
		(fp_line
			(start 0.7874 0.4064)
			(end -0.7874 0.4064)
			(stroke
				(width 0.1524)
				(type default)
			)
			(layer "F.SilkS")
		)
		(fp_line
			(start -0.67945 -0.305054)
			(end -0.12065 -0.305054)
			(stroke
				(width 0.1)
				(type default)
			)
			(layer "F.Fab")
		)
		(fp_line
			(start -0.67945 0.3048)
			(end -0.67945 -0.305054)
			(stroke
				(width 0.1)
				(type default)
			)
			(layer "F.Fab")
		)
		(fp_line
			(start -0.12065 -0.305054)
			(end -0.12065 -0.2794)
			(stroke
				(width 0.1)
				(type default)
			)
			(layer "F.Fab")
		)
		(fp_line
			(start -0.12065 -0.2794)
			(end 0.12065 -0.2794)
			(stroke
				(width 0.1)
				(type default)
			)
			(layer "F.Fab")
		)
		(fp_line
			(start -0.12065 0.2794)
			(end -0.12065 0.3048)
			(stroke
				(width 0.1)
				(type default)
			)
			(layer "F.Fab")
		)
		(fp_line
			(start -0.12065 0.3048)
			(end -0.67945 0.3048)
			(stroke
				(width 0.1)
				(type default)
			)
			(layer "F.Fab")
		)
		(fp_line
			(start 0.120396 0.2794)
			(end -0.12065 0.2794)
			(stroke
				(width 0.1)
				(type default)
			)
			(layer "F.Fab")
		)
		(fp_line
			(start 0.120396 0.3048)
			(end 0.120396 0.2794)
			(stroke
				(width 0.1)
				(type default)
			)
			(layer "F.Fab")
		)
		(fp_line
			(start 0.12065 -0.3048)
			(end 0.67945 -0.3048)
			(stroke
				(width 0.1)
				(type default)
			)
			(layer "F.Fab")
		)
		(fp_line
			(start 0.12065 -0.2794)
			(end 0.12065 -0.3048)
			(stroke
				(width 0.1)
				(type default)
			)
			(layer "F.Fab")
		)
		(fp_line
			(start 0.67945 -0.3048)
			(end 0.67945 0.3048)
			(stroke
				(width 0.1)
				(type default)
			)
			(layer "F.Fab")
		)
		(fp_line
			(start 0.67945 0.3048)
			(end 0.120396 0.3048)
			(stroke
				(width 0.1)
				(type default)
			)
			(layer "F.Fab")
		)
		(pad "1" smd circle
			(at -0.40005 0)
			(size 0 0)
			(layers "F.Cu" "F.Mask" "F.Paste")
			(net "P3V3_AUX")
		)
		(pad "2" smd circle
			(at 0.40005 0)
			(size 0 0)
			(layers "F.Cu" "F.Mask" "F.Paste")
			(net "PD_SMB_OCP2_HP_ADD2")
		)
	)
)
